#ISCELL
  pure_quanta quanta_title_block_c *
  *
#ISCELL
  logical_power universal_gnd *
  page40_i1
#CELL
  pure_quanta socket4677_azif0045p001c01cs *
  page40_i10
#CELL
  pure_quanta socket4677_azif0045p001c01cs *
  page40_i11
#CELL
  pure_quanta socket4677_azif0045p001c01cs *
  page40_i12
#ISCELL
  logical_power universal_gnd *
  page40_i3
#ISCELL
  logical_power universal_gnd *
  page40_i4
#ISCELL
  logical_power universal_gnd *
  page40_i6
#ISCELL
  logical_power universal_gnd *
  page40_i7
#ISCELL
  logical_power universal_gnd *
  page40_i9
